(kicad_pcb
	(version 20260206)
	(generator "pcbnew")
	(generator_version "10.0")
	(general
		(thickness 1.6)
		(legacy_teardrops no)
	)
	(paper "A4")
	(title_block
		(title "01162023_DA0F0TEBIF0_F0T_Expander_BD_F_brd_V02_OCP.brd")
		(comment 1 "Grand Teton / footprints 360-363 of 9728")
	)
	(layers
		(0 "F.Cu" signal "TOP")
		(4 "In1.Cu" signal "GND")
		(6 "In2.Cu" signal "VCC")
		(8 "In3.Cu" signal "VCC1")
		(10 "In4.Cu" signal "GND1")
		(12 "In5.Cu" signal "IN1")
		(14 "In6.Cu" signal "GND2")
		(16 "In7.Cu" signal "IN2")
		(18 "In8.Cu" signal "GND3")
		(20 "In9.Cu" signal "IN3")
		(22 "In10.Cu" signal "GND4")
		(24 "In11.Cu" signal "IN4")
		(26 "In12.Cu" signal "GND5")
		(28 "In13.Cu" signal "IN5")
		(30 "In14.Cu" signal "GND6")
		(32 "In15.Cu" signal "IN6")
		(34 "In16.Cu" signal "GND7")
		(2 "B.Cu" signal "BOTTOM")
		(9 "F.Adhes" user "F.Adhesive")
		(11 "B.Adhes" user "B.Adhesive")
		(13 "F.Paste" user "Package Geometry/Pastemask Top")
		(15 "B.Paste" user "Package Geometry/Pastemask Bottom")
		(5 "F.SilkS" user "Ref Des/Silkscreen Top")
		(7 "B.SilkS" user "Ref Des/Silkscreen Bottom")
		(1 "F.Mask" user "Board Geometry/Soldermask Top")
		(3 "B.Mask" user "Board Geometry/Soldermask Bottom")
		(17 "Dwgs.User" user "User.Drawings")
		(19 "Cmts.User" user "User.Comments")
		(21 "Eco1.User" user "User.Eco1")
		(23 "Eco2.User" user "User.Eco2")
		(25 "Edge.Cuts" user "Board Geometry/Outline")
		(27 "Margin" user)
		(31 "F.CrtYd" user "Package Geometry/Place Bound Top")
		(29 "B.CrtYd" user "Package Geometry/Place Bound Bottom")
		(35 "F.Fab" user "Ref Des/Assembly Top")
		(33 "B.Fab" user "Ref Des/Assembly Bottom")
	)
	(footprint ""
		(layer "F.Cu")
		(at 108.839 -85.979)
		(property "Reference" "U115"
			(at -3.7846 -4.03733 0)
			(unlocked yes)
			(layer "F.SilkS")
			(effects
				(font
					(size 0.7874 0.5842)
					(thickness 0.1524)
				)
				(justify left)
			)
		)
		(property "Value" ""
			(at 0 0 0)
			(layer "F.Fab")
			(effects
				(font
					(size 1.27 1.27)
				)
			)
		)
		(duplicate_pad_numbers_are_jumpers no)
		(fp_line
			(start -2.999994 -2.999994)
			(end -2.999994 -2.4384)
			(stroke
				(width 0.1524)
				(type default)
			)
			(layer "F.SilkS")
		)
		(fp_line
			(start -2.999994 2.4384)
			(end -2.999994 2.999994)
			(stroke
				(width 0.1524)
				(type default)
			)
			(layer "F.SilkS")
		)
		(fp_line
			(start -2.999994 2.999994)
			(end -2.4384 2.999994)
			(stroke
				(width 0.1524)
				(type default)
			)
			(layer "F.SilkS")
		)
		(fp_line
			(start -2.4384 -2.999994)
			(end -2.999994 -2.999994)
			(stroke
				(width 0.1524)
				(type default)
			)
			(layer "F.SilkS")
		)
		(fp_line
			(start 2.4384 2.999994)
			(end 2.999994 2.999994)
			(stroke
				(width 0.1524)
				(type default)
			)
			(layer "F.SilkS")
		)
		(fp_line
			(start 2.999994 -2.999994)
			(end 2.4384 -2.999994)
			(stroke
				(width 0.1524)
				(type default)
			)
			(layer "F.SilkS")
		)
		(fp_line
			(start 2.999994 -2.4384)
			(end 2.999994 -2.999994)
			(stroke
				(width 0.1524)
				(type default)
			)
			(layer "F.SilkS")
		)
		(fp_line
			(start 2.999994 2.999994)
			(end 2.999994 2.4384)
			(stroke
				(width 0.1524)
				(type default)
			)
			(layer "F.SilkS")
		)
		(fp_poly
			(pts
				(xy -4.318 -1.815338) (xy -4.318 -2.584704) (xy -3.548634 -2.199894)
			)
			(stroke
				(width 0)
				(type default)
			)
			(fill yes)
			(layer "F.SilkS")
		)
		(fp_line
			(start -2.999994 -2.999994)
			(end -2.999994 2.999994)
			(stroke
				(width 0.1)
				(type default)
			)
			(layer "F.Fab")
		)
		(fp_line
			(start -2.999994 2.999994)
			(end 2.999994 2.999994)
			(stroke
				(width 0.1)
				(type default)
			)
			(layer "F.Fab")
		)
		(fp_line
			(start 2.999994 -2.999994)
			(end -2.999994 -2.999994)
			(stroke
				(width 0.1)
				(type default)
			)
			(layer "F.Fab")
		)
		(fp_line
			(start 2.999994 2.999994)
			(end 2.999994 -2.999994)
			(stroke
				(width 0.1)
				(type default)
			)
			(layer "F.Fab")
		)
		(fp_poly
			(pts
				(xy -4.318 -1.815338) (xy -4.318 -2.584704) (xy -3.548634 -2.199894)
			)
			(stroke
				(width 0)
				(type default)
			)
			(fill yes)
			(layer "F.Fab")
		)
		(pad "1" smd circle
			(at -2.949956 -2.199894 270)
			(size 0 0)
			(layers "F.Cu" "F.Mask" "F.Paste")
			(net "FM_CLK_EN_R")
		)
		(pad "2" smd circle
			(at -2.949956 -1.800098 270)
			(size 0 0)
			(layers "F.Cu" "F.Mask" "F.Paste")
			(net "GND")
		)
		(pad "3" smd circle
			(at -2.949956 -1.400048 270)
			(size 0 0)
			(layers "F.Cu" "F.Mask" "F.Paste")
			(net "P3V3_VDDAR_9ZXL0851_0_7")
		)
		(pad "4" smd circle
			(at -2.949956 -0.999998 270)
			(size 0 0)
			(layers "F.Cu" "F.Mask" "F.Paste")
			(net "CLK_100M_CK440Q_1_DB800ZL_R_DP")
		)
		(pad "5" smd circle
			(at -2.949956 -0.599948 270)
			(size 0 0)
			(layers "F.Cu" "F.Mask" "F.Paste")
			(net "CLK_100M_CK440Q_1_DB800ZL_R_DN")
		)
		(pad "6" smd circle
			(at -2.949956 -0.199898 270)
			(size 0 0)
			(layers "F.Cu" "F.Mask" "F.Paste")
			(net "SMB_BMC_9ZXL0851_0_7_SDA")
		)
		(pad "7" smd circle
			(at -2.949956 0.199898 270)
			(size 0 0)
			(layers "F.Cu" "F.Mask" "F.Paste")
			(net "SMB_BMC_9ZXL0851_0_7_SCL")
		)
		(pad "8" smd circle
			(at -2.949956 0.599948 270)
			(size 0 0)
			(layers "F.Cu" "F.Mask" "F.Paste")
			(net "Net_4340")
		)
		(pad "9" smd circle
			(at -2.949956 0.999998 270)
			(size 0 0)
			(layers "F.Cu" "F.Mask" "F.Paste")
			(net "Net_4339")
		)
		(pad "10" smd circle
			(at -2.949956 1.400048 270)
			(size 0 0)
			(layers "F.Cu" "F.Mask" "F.Paste")
			(net "P3V3_VDD_9ZXL0851_0_7")
		)
		(pad "11" smd circle
			(at -2.949956 1.800098 270)
			(size 0 0)
			(layers "F.Cu" "F.Mask" "F.Paste")
			(net "SSD0_CLK_EN_R_N")
		)
		(pad "12" smd circle
			(at -2.949956 2.199894 270)
			(size 0 0)
			(layers "F.Cu" "F.Mask" "F.Paste")
			(net "Net_4341")
		)
		(pad "13" smd circle
			(at -2.199894 2.949956)
			(size 0 0)
			(layers "F.Cu" "F.Mask" "F.Paste")
			(net "CLK_100M_DB800ZL_SSD0_DP")
		)
		(pad "14" smd circle
			(at -1.800098 2.949956)
			(size 0 0)
			(layers "F.Cu" "F.Mask" "F.Paste")
			(net "CLK_100M_DB800ZL_SSD0_DN")
		)
		(pad "15" smd circle
			(at -1.400048 2.949956)
			(size 0 0)
			(layers "F.Cu" "F.Mask" "F.Paste")
			(net "P3V3_VDD_9ZXL0851_0_7")
		)
		(pad "16" smd circle
			(at -0.999998 2.949956)
			(size 0 0)
			(layers "F.Cu" "F.Mask" "F.Paste")
			(net "CLK_100M_DB800ZL_SSD1_DP")
		)
		(pad "17" smd circle
			(at -0.599948 2.949956)
			(size 0 0)
			(layers "F.Cu" "F.Mask" "F.Paste")
			(net "CLK_100M_DB800ZL_SSD1_DN")
		)
		(pad "18" smd circle
			(at -0.199898 2.949956)
			(size 0 0)
			(layers "F.Cu" "F.Mask" "F.Paste")
			(net "SSD1_CLK_EN_R_N")
		)
		(pad "19" smd circle
			(at 0.199898 2.949956)
			(size 0 0)
			(layers "F.Cu" "F.Mask" "F.Paste")
			(net "P3V3_VDD_9ZXL0851_0_7")
		)
		(pad "20" smd circle
			(at 0.599948 2.949956)
			(size 0 0)
			(layers "F.Cu" "F.Mask" "F.Paste")
			(net "Net_4342")
		)
		(pad "21" smd circle
			(at 0.999998 2.949956)
			(size 0 0)
			(layers "F.Cu" "F.Mask" "F.Paste")
			(net "CLK_100M_DB800ZL_SSD2_DP")
		)
		(pad "22" smd circle
			(at 1.400048 2.949956)
			(size 0 0)
			(layers "F.Cu" "F.Mask" "F.Paste")
			(net "CLK_100M_DB800ZL_SSD2_DN")
		)
		(pad "23" smd circle
			(at 1.800098 2.949956)
			(size 0 0)
			(layers "F.Cu" "F.Mask" "F.Paste")
			(net "SSD2_CLK_EN_R_N")
		)
		(pad "24" smd circle
			(at 2.199894 2.949956)
			(size 0 0)
			(layers "F.Cu" "F.Mask" "F.Paste")
			(net "SSD3_CLK_EN_R_N")
		)
		(pad "25" smd circle
			(at 2.949956 2.199894 90)
			(size 0 0)
			(layers "F.Cu" "F.Mask" "F.Paste")
			(net "CLK_100M_DB800ZL_SSD3_DP")
		)
		(pad "26" smd circle
			(at 2.949956 1.800098 90)
			(size 0 0)
			(layers "F.Cu" "F.Mask" "F.Paste")
			(net "CLK_100M_DB800ZL_SSD3_DN")
		)
		(pad "27" smd circle
			(at 2.949956 1.400048 90)
			(size 0 0)
			(layers "F.Cu" "F.Mask" "F.Paste")
			(net "P3V3_VDD_9ZXL0851_0_7")
		)
		(pad "28" smd circle
			(at 2.949956 0.999998 90)
			(size 0 0)
			(layers "F.Cu" "F.Mask" "F.Paste")
			(net "CLK_100M_DB800ZL_SSD4_DP")
		)
		(pad "29" smd circle
			(at 2.949956 0.599948 90)
			(size 0 0)
			(layers "F.Cu" "F.Mask" "F.Paste")
			(net "CLK_100M_DB800ZL_SSD4_DN")
		)
		(pad "30" smd circle
			(at 2.949956 0.199898 90)
			(size 0 0)
			(layers "F.Cu" "F.Mask" "F.Paste")
			(net "SSD4_CLK_EN_R_N")
		)
		(pad "31" smd circle
			(at 2.949956 -0.199898 90)
			(size 0 0)
			(layers "F.Cu" "F.Mask" "F.Paste")
			(net "SSD5_CLK_EN_R_N")
		)
		(pad "32" smd circle
			(at 2.949956 -0.599948 90)
			(size 0 0)
			(layers "F.Cu" "F.Mask" "F.Paste")
			(net "CLK_100M_DB800ZL_SSD5_DP")
		)
		(pad "33" smd circle
			(at 2.949956 -0.999998 90)
			(size 0 0)
			(layers "F.Cu" "F.Mask" "F.Paste")
			(net "CLK_100M_DB800ZL_SSD5_DN")
		)
		(pad "34" smd circle
			(at 2.949956 -1.400048 90)
			(size 0 0)
			(layers "F.Cu" "F.Mask" "F.Paste")
			(net "P3V3_VDD_9ZXL0851_0_7")
		)
		(pad "35" smd circle
			(at 2.949956 -1.800098 90)
			(size 0 0)
			(layers "F.Cu" "F.Mask" "F.Paste")
			(net "CLK_100M_DB800ZL_SSD6_DP")
		)
		(pad "36" smd circle
			(at 2.949956 -2.199894 90)
			(size 0 0)
			(layers "F.Cu" "F.Mask" "F.Paste")
			(net "CLK_100M_DB800ZL_SSD6_DN")
		)
		(pad "37" smd circle
			(at 2.199894 -2.949956 180)
			(size 0 0)
			(layers "F.Cu" "F.Mask" "F.Paste")
			(net "SSD6_CLK_EN_R_N")
		)
		(pad "38" smd circle
			(at 1.800098 -2.949956 180)
			(size 0 0)
			(layers "F.Cu" "F.Mask" "F.Paste")
			(net "P3V3_VDD_9ZXL0851_0_7")
		)
		(pad "39" smd circle
			(at 1.400048 -2.949956 180)
			(size 0 0)
			(layers "F.Cu" "F.Mask" "F.Paste")
			(net "CLK_100M_DB800ZL_SSD7_DP")
		)
		(pad "40" smd circle
			(at 0.999998 -2.949956 180)
			(size 0 0)
			(layers "F.Cu" "F.Mask" "F.Paste")
			(net "CLK_100M_DB800ZL_SSD7_DN")
		)
		(pad "41" smd circle
			(at 0.599948 -2.949956 180)
			(size 0 0)
			(layers "F.Cu" "F.Mask" "F.Paste")
			(net "SSD7_CLK_EN_R_N")
		)
		(pad "42" smd circle
			(at 0.199898 -2.949956 180)
			(size 0 0)
			(layers "F.Cu" "F.Mask" "F.Paste")
			(net "P3V3_VDD_9ZXL0851_0_7")
		)
		(pad "43" smd circle
			(at -0.199898 -2.949956 180)
			(size 0 0)
			(layers "F.Cu" "F.Mask" "F.Paste")
			(net "Net_4343")
		)
		(pad "44" smd circle
			(at -0.599948 -2.949956 180)
			(size 0 0)
			(layers "F.Cu" "F.Mask" "F.Paste")
			(net "P3V3_VDDAR_9ZXL0851_0_7")
		)
		(pad "45" smd circle
			(at -0.999998 -2.949956 180)
			(size 0 0)
			(layers "F.Cu" "F.Mask" "F.Paste")
			(net "Net_4344")
		)
		(pad "46" smd circle
			(at -1.400048 -2.949956 180)
			(size 0 0)
			(layers "F.Cu" "F.Mask" "F.Paste")
			(net "Net_4345")
		)
		(pad "47" smd circle
			(at -1.800098 -2.949956 180)
			(size 0 0)
			(layers "F.Cu" "F.Mask" "F.Paste")
			(net "PU_9ZXL0851_0_7_100M")
		)
		(pad "48" smd circle
			(at -2.199894 -2.949956 180)
			(size 0 0)
			(layers "F.Cu" "F.Mask" "F.Paste")
			(net "PU_9ZXL0851_0_7_HBW")
		)
		(pad "49" smd rect
			(at 0 0)
			(size 4.2164 4.2164)
			(layers "F.Cu" "F.Mask" "F.Paste")
			(net "GND")
		)
		(zone
			(layer "F.Cu")
			(hatch none 0.5)
			(connect_pads
				(clearance 0)
			)
			(min_thickness 0.25)
			(keepout
				(tracks not_allowed)
				(vias allowed)
				(pads allowed)
				(copperpour not_allowed)
				(footprints allowed)
			)
			(placement
				(enabled no)
				(sheetname "")
			)
			(fill
				(thermal_gap 0.5)
				(thermal_bridge_width 0.5)
				(island_removal_mode 0)
			)
			(polygon
				(pts
					(xy 106.3752 -86.9442) (xy 106.3752 -83.5152) (xy 111.3028 -83.5152) (xy 111.3028 -88.4428) (xy 106.3752 -88.4428)
					(xy 106.3752 -86.9696) (xy 106.68 -86.9696) (xy 106.68 -88.138) (xy 110.998 -88.138) (xy 110.998 -83.82)
					(xy 106.68 -83.82) (xy 106.68 -86.9442)
				)
			)
		)
	)
	(footprint ""
		(layer "F.Cu")
		(at 145.593562 -237.971838 -90)
		(property "Reference" "C4419"
			(at 0 0 270)
			(layer "F.SilkS")
			(hide yes)
			(effects
				(font
					(size 1.27 1.27)
				)
			)
		)
		(property "Value" ""
			(at 0 0 270)
			(layer "F.Fab")
			(effects
				(font
					(size 1.27 1.27)
				)
			)
		)
		(duplicate_pad_numbers_are_jumpers no)
		(fp_line
			(start -0.7874 0.4064)
			(end -0.7874 -0.4064)
			(stroke
				(width 0.1524)
				(type default)
			)
			(layer "F.SilkS")
		)
		(fp_line
			(start 0.7874 0.4064)
			(end -0.7874 0.4064)
			(stroke
				(width 0.1524)
				(type default)
			)
			(layer "F.SilkS")
		)
		(fp_line
			(start -0.7874 -0.4064)
			(end 0.7874 -0.4064)
			(stroke
				(width 0.1524)
				(type default)
			)
			(layer "F.SilkS")
		)
		(fp_line
			(start 0.7874 -0.4064)
			(end 0.7874 0.4064)
			(stroke
				(width 0.1524)
				(type default)
			)
			(layer "F.SilkS")
		)
		(fp_line
			(start -0.67945 0.3048)
			(end -0.67945 -0.305054)
			(stroke
				(width 0.1)
				(type default)
			)
			(layer "F.Fab")
		)
		(fp_line
			(start -0.12065 0.3048)
			(end -0.67945 0.3048)
			(stroke
				(width 0.1)
				(type default)
			)
			(layer "F.Fab")
		)
		(fp_line
			(start 0.120396 0.3048)
			(end 0.120396 0.2794)
			(stroke
				(width 0.1)
				(type default)
			)
			(layer "F.Fab")
		)
		(fp_line
			(start 0.67945 0.3048)
			(end 0.120396 0.3048)
			(stroke
				(width 0.1)
				(type default)
			)
			(layer "F.Fab")
		)
		(fp_line
			(start -0.12065 0.2794)
			(end -0.12065 0.3048)
			(stroke
				(width 0.1)
				(type default)
			)
			(layer "F.Fab")
		)
		(fp_line
			(start 0.120396 0.2794)
			(end -0.12065 0.2794)
			(stroke
				(width 0.1)
				(type default)
			)
			(layer "F.Fab")
		)
		(fp_line
			(start -0.12065 -0.2794)
			(end 0.12065 -0.2794)
			(stroke
				(width 0.1)
				(type default)
			)
			(layer "F.Fab")
		)
		(fp_line
			(start 0.12065 -0.2794)
			(end 0.12065 -0.3048)
			(stroke
				(width 0.1)
				(type default)
			)
			(layer "F.Fab")
		)
		(fp_line
			(start 0.12065 -0.3048)
			(end 0.67945 -0.3048)
			(stroke
				(width 0.1)
				(type default)
			)
			(layer "F.Fab")
		)
		(fp_line
			(start 0.67945 -0.3048)
			(end 0.67945 0.3048)
			(stroke
				(width 0.1)
				(type default)
			)
			(layer "F.Fab")
		)
		(fp_line
			(start -0.67945 -0.305054)
			(end -0.12065 -0.305054)
			(stroke
				(width 0.1)
				(type default)
			)
			(layer "F.Fab")
		)
		(fp_line
			(start -0.12065 -0.305054)
			(end -0.12065 -0.2794)
			(stroke
				(width 0.1)
				(type default)
			)
			(layer "F.Fab")
		)
		(pad "1" smd circle
			(at -0.40005 0 270)
			(size 0 0)
			(layers "F.Cu" "F.Mask" "F.Paste")
			(net "P5V_AUX")
		)
		(pad "2" smd circle
			(at 0.40005 0 270)
			(size 0 0)
			(layers "F.Cu" "F.Mask" "F.Paste")
			(net "GND")
		)
	)
	(footprint ""
		(layer "F.Cu")
		(at 232.784142 -29.222954 -90)
		(property "Reference" "PC938"
			(at 0 0 270)
			(layer "F.SilkS")
			(hide yes)
			(effects
				(font
					(size 1.27 1.27)
				)
			)
		)
		(property "Value" ""
			(at 0 0 270)
			(layer "F.Fab")
			(effects
				(font
					(size 1.27 1.27)
				)
			)
		)
		(duplicate_pad_numbers_are_jumpers no)
		(fp_line
			(start -0.7874 0.4064)
			(end -0.7874 -0.4064)
			(stroke
				(width 0.1524)
				(type default)
			)
			(layer "F.SilkS")
		)
		(fp_line
			(start 0.7874 0.4064)
			(end -0.7874 0.4064)
			(stroke
				(width 0.1524)
				(type default)
			)
			(layer "F.SilkS")
		)
		(fp_line
			(start -0.7874 -0.4064)
			(end 0.7874 -0.4064)
			(stroke
				(width 0.1524)
				(type default)
			)
			(layer "F.SilkS")
		)
		(fp_line
			(start 0.7874 -0.4064)
			(end 0.7874 0.4064)
			(stroke
				(width 0.1524)
				(type default)
			)
			(layer "F.SilkS")
		)
		(fp_line
			(start -0.67945 0.3048)
			(end -0.67945 -0.305054)
			(stroke
				(width 0.1)
				(type default)
			)
			(layer "F.Fab")
		)
		(fp_line
			(start -0.12065 0.3048)
			(end -0.67945 0.3048)
			(stroke
				(width 0.1)
				(type default)
			)
			(layer "F.Fab")
		)
		(fp_line
			(start 0.120396 0.3048)
			(end 0.120396 0.2794)
			(stroke
				(width 0.1)
				(type default)
			)
			(layer "F.Fab")
		)
		(fp_line
			(start 0.67945 0.3048)
			(end 0.120396 0.3048)
			(stroke
				(width 0.1)
				(type default)
			)
			(layer "F.Fab")
		)
		(fp_line
			(start -0.12065 0.2794)
			(end -0.12065 0.3048)
			(stroke
				(width 0.1)
				(type default)
			)
			(layer "F.Fab")
		)
		(fp_line
			(start 0.120396 0.2794)
			(end -0.12065 0.2794)
			(stroke
				(width 0.1)
				(type default)
			)
			(layer "F.Fab")
		)
		(fp_line
			(start -0.12065 -0.2794)
			(end 0.12065 -0.2794)
			(stroke
				(width 0.1)
				(type default)
			)
			(layer "F.Fab")
		)
		(fp_line
			(start 0.12065 -0.2794)
			(end 0.12065 -0.3048)
			(stroke
				(width 0.1)
				(type default)
			)
			(layer "F.Fab")
		)
		(fp_line
			(start 0.12065 -0.3048)
			(end 0.67945 -0.3048)
			(stroke
				(width 0.1)
				(type default)
			)
			(layer "F.Fab")
		)
		(fp_line
			(start 0.67945 -0.3048)
			(end 0.67945 0.3048)
			(stroke
				(width 0.1)
				(type default)
			)
			(layer "F.Fab")
		)
		(fp_line
			(start -0.67945 -0.305054)
			(end -0.12065 -0.305054)
			(stroke
				(width 0.1)
				(type default)
			)
			(layer "F.Fab")
		)
		(fp_line
			(start -0.12065 -0.305054)
			(end -0.12065 -0.2794)
			(stroke
				(width 0.1)
				(type default)
			)
			(layer "F.Fab")
		)
		(pad "1" smd circle
			(at -0.40005 0 270)
			(size 0 0)
			(layers "F.Cu" "F.Mask" "F.Paste")
			(net "P3V3_AUX")
		)
		(pad "2" smd circle
			(at 0.40005 0 270)
			(size 0 0)
			(layers "F.Cu" "F.Mask" "F.Paste")
			(net "GND")
		)
	)
	(footprint ""
		(layer "F.Cu")
		(at 480.844098 -550.674794 180)
		(property "Reference" "JPEX2_FW1"
			(at -4.0259 -1.402334 0)
			(unlocked yes)
			(layer "B.SilkS")
			(effects
				(font
					(size 0.7874 0.5842)
					(thickness 0.1524)
				)
				(justify mirror)
			)
		)
		(property "Value" ""
			(at 0 0 180)
			(layer "F.Fab")
			(effects
				(font
					(size 1.27 1.27)
				)
			)
		)
		(duplicate_pad_numbers_are_jumpers no)
		(pad "1" thru_hole circle
			(at 0 0 180)
			(size 0.4572 0.4572)
			(drill 0.2032)
			(layers "*.Cu" "*.Mask")
			(remove_unused_layers no)
			(net "Net_9088")
			(clearance 0.127)
			(thermal_gap 0.127)
			(padstack
				(mode front_inner_back)
				(layer "Inner"
					(shape circle)
					(size 0.4572 0.4572)
					(clearance 0.127)
				)
				(layer "B.Cu"
					(shape circle)
					(size 0.508 0.508)
					(clearance 0.1016)
				)
			)
		)
	)
)
